(kicad_pcb
	(version 20260206)
	(generator "pcbnew")
	(generator_version "10.0")
	(general
		(thickness 1.6)
		(legacy_teardrops no)
	)
	(paper "A4")
	(title_block
		(title "netronome-mezz — pcbd0082-001_rev01_jul9_a.brd")
		(comment 1 "Open CloudServer (Microsoft) / footprints 85-87 of 714")
	)
	(layers
		(0 "F.Cu" signal "TOP")
		(4 "In1.Cu" signal "02_GND")
		(6 "In2.Cu" signal "03_SIG")
		(8 "In3.Cu" signal "04_SIG")
		(10 "In4.Cu" signal "05_GND")
		(12 "In5.Cu" signal "06_PWR1")
		(14 "In6.Cu" signal "07_SIG")
		(16 "In7.Cu" signal "08_SIG")
		(18 "In8.Cu" signal "09_GND")
		(2 "B.Cu" signal "BOTTOM")
		(9 "F.Adhes" user "F.Adhesive")
		(11 "B.Adhes" user "B.Adhesive")
		(13 "F.Paste" user "Package Geometry/Pastemask Top")
		(15 "B.Paste" user "Package Geometry/Pastemask Bottom")
		(5 "F.SilkS" user "Ref Des/Silkscreen Top")
		(7 "B.SilkS" user "Ref Des/Silkscreen Bottom")
		(1 "F.Mask" user "Board Geometry/Soldermask Top")
		(3 "B.Mask" user "Board Geometry/Soldermask Bottom")
		(17 "Dwgs.User" user "User.Drawings")
		(19 "Cmts.User" user "User.Comments")
		(21 "Eco1.User" user "User.Eco1")
		(23 "Eco2.User" user "User.Eco2")
		(25 "Edge.Cuts" user "Board Geometry/Outline")
		(27 "Margin" user)
		(31 "F.CrtYd" user "Package Geometry/Place Bound Top")
		(29 "B.CrtYd" user "Package Geometry/Place Bound Bottom")
		(35 "F.Fab" user "Ref Des/Assembly Top")
		(33 "B.Fab" user "Ref Des/Assembly Bottom")
		(45 "User.4" user "COMPVAL_TYPE_BOTTOM")
	)
	(footprint ""
		(layer "F.Cu")
		(at 22.606 32.893 180)
		(property "Reference" "U12"
			(at 3.683 2.38633 0)
			(unlocked yes)
			(layer "F.SilkS")
			(effects
				(font
					(size 0.7874 0.5842)
					(thickness 0.127)
				)
				(justify left)
			)
		)
		(property "Value" "*"
			(at -0.4826 -0.148107 180)
			(unlocked yes)
			(layer "F.Fab")
			(hide yes)
			(effects
				(font
					(size 1.27 0.9652)
					(thickness 0.000001)
				)
				(justify left)
			)
		)
		(property "Device Type" "ICSO0128"
			(at -0.4826 -0.148107 180)
			(unlocked yes)
			(layer "F.Fab")
			(hide yes)
			(effects
				(font
					(size 1.27 0.9652)
					(thickness 0.000001)
				)
				(justify left)
			)
		)
		(duplicate_pad_numbers_are_jumpers no)
		(fp_line
			(start 2.159 1.651)
			(end 2.159 0.762)
			(stroke
				(width 0.1524)
				(type default)
			)
			(layer "F.SilkS")
		)
		(fp_line
			(start 2.159 1.651)
			(end 2.159 0.762)
			(stroke
				(width 0.1524)
				(type default)
			)
			(layer "F.SilkS")
		)
		(fp_line
			(start 2.159 -1.651)
			(end 2.159 -0.762)
			(stroke
				(width 0.1524)
				(type default)
			)
			(layer "F.SilkS")
		)
		(fp_line
			(start 2.159 -1.651)
			(end 2.159 -0.762)
			(stroke
				(width 0.1524)
				(type default)
			)
			(layer "F.SilkS")
		)
		(fp_line
			(start 1.778 1.651)
			(end 2.159 1.651)
			(stroke
				(width 0.1524)
				(type default)
			)
			(layer "F.SilkS")
		)
		(fp_line
			(start 1.778 -1.651)
			(end 2.159 -1.651)
			(stroke
				(width 0.1524)
				(type default)
			)
			(layer "F.SilkS")
		)
		(fp_line
			(start -1.778 1.651)
			(end -2.159 1.651)
			(stroke
				(width 0.1524)
				(type default)
			)
			(layer "F.SilkS")
		)
		(fp_line
			(start -1.778 1.651)
			(end -2.159 1.143)
			(stroke
				(width 0.1524)
				(type default)
			)
			(layer "F.SilkS")
		)
		(fp_line
			(start -1.778 -1.651)
			(end -2.159 -1.651)
			(stroke
				(width 0.1524)
				(type default)
			)
			(layer "F.SilkS")
		)
		(fp_line
			(start -2.159 1.651)
			(end -2.159 0.762)
			(stroke
				(width 0.1524)
				(type default)
			)
			(layer "F.SilkS")
		)
		(fp_line
			(start -2.159 -1.651)
			(end -2.159 -0.762)
			(stroke
				(width 0.1524)
				(type default)
			)
			(layer "F.SilkS")
		)
		(fp_arc
			(start -1.651 2.159)
			(mid -1.725395 2.338605)
			(end -1.905 2.413)
			(stroke
				(width 0.1524)
				(type default)
			)
			(layer "F.SilkS")
		)
		(fp_arc
			(start -1.70213 2.006168)
			(mid -1.664125 2.078422)
			(end -1.651 2.159)
			(stroke
				(width 0.1524)
				(type default)
			)
			(layer "F.SilkS")
		)
		(fp_arc
			(start -1.905 2.413)
			(mid -2.084605 2.338605)
			(end -2.159 2.159)
			(stroke
				(width 0.1524)
				(type default)
			)
			(layer "F.SilkS")
		)
		(fp_arc
			(start -2.159 2.159)
			(mid -2.15698 2.127227)
			(end -2.150999 2.095957)
			(stroke
				(width 0.1524)
				(type default)
			)
			(layer "F.SilkS")
		)
		(fp_circle
			(center -1.905 2.159)
			(end -2.159 2.159)
			(stroke
				(width 0.1524)
				(type default)
			)
			(fill no)
			(layer "F.SilkS")
		)
		(fp_poly
			(pts
				(xy -2.667 2.159) (xy 2.667 2.159) (xy 2.667 -2.159) (xy -2.667 -2.159)
			)
			(stroke
				(width 0)
				(type default)
			)
			(fill no)
			(layer "F.CrtYd")
		)
		(fp_line
			(start 1.8034 1.2954)
			(end 1.8034 -1.2954)
			(stroke
				(width 0.1524)
				(type default)
			)
			(layer "F.Fab")
		)
		(fp_line
			(start 1.8034 -1.2954)
			(end -1.8034 -1.2954)
			(stroke
				(width 0.1524)
				(type default)
			)
			(layer "F.Fab")
		)
		(fp_line
			(start -1.8034 1.2954)
			(end 1.8034 1.2954)
			(stroke
				(width 0.1524)
				(type default)
			)
			(layer "F.Fab")
		)
		(fp_line
			(start -1.8034 -1.2954)
			(end -1.8034 1.2954)
			(stroke
				(width 0.1524)
				(type default)
			)
			(layer "F.Fab")
		)
		(fp_circle
			(center -1.27 0.762)
			(end -1.553997 0.762)
			(stroke
				(width 0.1524)
				(type default)
			)
			(fill no)
			(layer "F.Fab")
		)
		(fp_text user "10"
			(at 3.683 -1.67767 0)
			(unlocked yes)
			(layer "F.SilkS")
			(effects
				(font
					(size 0.7874 0.5842)
					(thickness 0.127)
				)
				(justify left)
			)
		)
		(fp_text user "8"
			(at 2.8829 1.251814 0)
			(unlocked yes)
			(layer "F.SilkS")
			(effects
				(font
					(size 0.7874 0.5842)
					(thickness 0.127)
				)
				(justify left)
			)
		)
		(fp_text user "9"
			(at 2.794 -0.15367 0)
			(unlocked yes)
			(layer "F.SilkS")
			(effects
				(font
					(size 0.7874 0.5842)
					(thickness 0.127)
				)
				(justify left)
			)
		)
		(fp_text user "7"
			(at 0.86233 1.905 90)
			(unlocked yes)
			(layer "F.SilkS")
			(effects
				(font
					(size 0.7874 0.5842)
					(thickness 0.127)
				)
				(justify left)
			)
		)
		(fp_text user "2"
			(at -0.889 2.38633 0)
			(unlocked yes)
			(layer "F.SilkS")
			(effects
				(font
					(size 0.7874 0.5842)
					(thickness 0.127)
				)
				(justify left)
			)
		)
		(fp_text user "15"
			(at -1.397 -1.80467 0)
			(unlocked yes)
			(layer "F.SilkS")
			(effects
				(font
					(size 0.7874 0.5842)
					(thickness 0.127)
				)
				(justify left)
			)
		)
		(fp_text user "1"
			(at -2.159 0.60833 0)
			(unlocked yes)
			(layer "F.SilkS")
			(effects
				(font
					(size 0.7874 0.5842)
					(thickness 0.127)
				)
				(justify left)
			)
		)
		(fp_text user "16"
			(at -2.159 -0.53467 0)
			(unlocked yes)
			(layer "F.SilkS")
			(effects
				(font
					(size 0.7874 0.5842)
					(thickness 0.127)
				)
				(justify left)
			)
		)
		(pad "1" smd custom
			(at -1.7018 0.250012 90)
			(size 0.06985 0.06985)
			(layers "F.Cu" "F.Mask" "F.Paste")
			(net "CPLD_PGRM_JTAG_SEL")
			(options
				(clearance outline)
				(anchor circle)
			)
			(primitives
				(gr_poly
					(pts
						(xy 0.1397 0.4064)
						(arc
							(start 0.1397 -0.2667)
							(mid 0 -0.4064)
							(end -0.1397 -0.2667)
						)
						(xy -0.1397 0.4064)
					)
					(width 0)
					(fill yes)
				)
			)
		)
		(pad "2" smd custom
			(at -1.25001 1.1938 180)
			(size 0.06985 0.06985)
			(layers "F.Cu" "F.Mask" "F.Paste")
			(net "DEBUG_CPLD_PGRM_JTAG_TCK")
			(options
				(clearance outline)
				(anchor circle)
			)
			(primitives
				(gr_poly
					(pts
						(xy 0.1397 0.4064)
						(arc
							(start 0.1397 -0.2667)
							(mid 0 -0.4064)
							(end -0.1397 -0.2667)
						)
						(xy -0.1397 0.4064)
					)
					(width 0)
					(fill yes)
				)
			)
		)
		(pad "3" smd custom
			(at -0.750011 1.1938 180)
			(size 0.06985 0.06985)
			(layers "F.Cu" "F.Mask" "F.Paste")
			(net "NFP_CPLD_PRGM_JTAG_TCK")
			(options
				(clearance outline)
				(anchor circle)
			)
			(primitives
				(gr_poly
					(pts
						(xy 0.1397 0.4064)
						(arc
							(start 0.1397 -0.2667)
							(mid 0 -0.4064)
							(end -0.1397 -0.2667)
						)
						(xy -0.1397 0.4064)
					)
					(width 0)
					(fill yes)
				)
			)
		)
		(pad "4" smd custom
			(at -0.250012 1.1938 180)
			(size 0.06985 0.06985)
			(layers "F.Cu" "F.Mask" "F.Paste")
			(net "CPLD_PGRM_JTAG_TCK")
			(options
				(clearance outline)
				(anchor circle)
			)
			(primitives
				(gr_poly
					(pts
						(xy 0.1397 0.4064)
						(arc
							(start 0.1397 -0.2667)
							(mid 0 -0.4064)
							(end -0.1397 -0.2667)
						)
						(xy -0.1397 0.4064)
					)
					(width 0)
					(fill yes)
				)
			)
		)
		(pad "5" smd custom
			(at 0.250012 1.1938 180)
			(size 0.06985 0.06985)
			(layers "F.Cu" "F.Mask" "F.Paste")
			(net "DEBUG_CPLD_PGRM_JTAG_TDI")
			(options
				(clearance outline)
				(anchor circle)
			)
			(primitives
				(gr_poly
					(pts
						(xy 0.1397 0.4064)
						(arc
							(start 0.1397 -0.2667)
							(mid 0 -0.4064)
							(end -0.1397 -0.2667)
						)
						(xy -0.1397 0.4064)
					)
					(width 0)
					(fill yes)
				)
			)
		)
		(pad "6" smd custom
			(at 0.750011 1.1938 180)
			(size 0.06985 0.06985)
			(layers "F.Cu" "F.Mask" "F.Paste")
			(net "NFP_CPLD_PRGM_JTAG_TDI")
			(options
				(clearance outline)
				(anchor circle)
			)
			(primitives
				(gr_poly
					(pts
						(xy 0.1397 0.4064)
						(arc
							(start 0.1397 -0.2667)
							(mid 0 -0.4064)
							(end -0.1397 -0.2667)
						)
						(xy -0.1397 0.4064)
					)
					(width 0)
					(fill yes)
				)
			)
		)
		(pad "7" smd custom
			(at 1.25001 1.1938 180)
			(size 0.06985 0.06985)
			(layers "F.Cu" "F.Mask" "F.Paste")
			(net "CPLD_PGRM_JTAG_TDI")
			(options
				(clearance outline)
				(anchor circle)
			)
			(primitives
				(gr_poly
					(pts
						(xy 0.1397 0.4064)
						(arc
							(start 0.1397 -0.2667)
							(mid 0 -0.4064)
							(end -0.1397 -0.2667)
						)
						(xy -0.1397 0.4064)
					)
					(width 0)
					(fill yes)
				)
			)
		)
		(pad "8" smd custom
			(at 1.7018 0.250012 270)
			(size 0.06985 0.06985)
			(layers "F.Cu" "F.Mask" "F.Paste")
			(net "GND")
			(options
				(clearance outline)
				(anchor circle)
			)
			(primitives
				(gr_poly
					(pts
						(xy 0.1397 0.4064)
						(arc
							(start 0.1397 -0.2667)
							(mid 0 -0.4064)
							(end -0.1397 -0.2667)
						)
						(xy -0.1397 0.4064)
					)
					(width 0)
					(fill yes)
				)
			)
		)
		(pad "9" smd custom
			(at 1.7018 -0.250012 270)
			(size 0.06985 0.06985)
			(layers "F.Cu" "F.Mask" "F.Paste")
			(net "CPLD_PGRM_JTAG_TDO")
			(options
				(clearance outline)
				(anchor circle)
			)
			(primitives
				(gr_poly
					(pts
						(xy 0.1397 0.4064)
						(arc
							(start 0.1397 -0.2667)
							(mid 0 -0.4064)
							(end -0.1397 -0.2667)
						)
						(xy -0.1397 0.4064)
					)
					(width 0)
					(fill yes)
				)
			)
		)
		(pad "10" smd custom
			(at 1.25001 -1.1938)
			(size 0.06985 0.06985)
			(layers "F.Cu" "F.Mask" "F.Paste")
			(net "NFP_CPLD_PRGM_JTAG_TDO")
			(options
				(clearance outline)
				(anchor circle)
			)
			(primitives
				(gr_poly
					(pts
						(xy 0.1397 0.4064)
						(arc
							(start 0.1397 -0.2667)
							(mid 0 -0.4064)
							(end -0.1397 -0.2667)
						)
						(xy -0.1397 0.4064)
					)
					(width 0)
					(fill yes)
				)
			)
		)
		(pad "11" smd custom
			(at 0.750011 -1.1938)
			(size 0.06985 0.06985)
			(layers "F.Cu" "F.Mask" "F.Paste")
			(net "DEBUG_CPLD_PGRM_JTAG_TDO")
			(options
				(clearance outline)
				(anchor circle)
			)
			(primitives
				(gr_poly
					(pts
						(xy 0.1397 0.4064)
						(arc
							(start 0.1397 -0.2667)
							(mid 0 -0.4064)
							(end -0.1397 -0.2667)
						)
						(xy -0.1397 0.4064)
					)
					(width 0)
					(fill yes)
				)
			)
		)
		(pad "12" smd custom
			(at 0.250012 -1.1938)
			(size 0.06985 0.06985)
			(layers "F.Cu" "F.Mask" "F.Paste")
			(net "CPLD_PGRM_JTAG_TMS")
			(options
				(clearance outline)
				(anchor circle)
			)
			(primitives
				(gr_poly
					(pts
						(xy 0.1397 0.4064)
						(arc
							(start 0.1397 -0.2667)
							(mid 0 -0.4064)
							(end -0.1397 -0.2667)
						)
						(xy -0.1397 0.4064)
					)
					(width 0)
					(fill yes)
				)
			)
		)
		(pad "13" smd custom
			(at -0.250012 -1.1938)
			(size 0.06985 0.06985)
			(layers "F.Cu" "F.Mask" "F.Paste")
			(net "NFP_CPLD_PRGM_JTAG_TMS")
			(options
				(clearance outline)
				(anchor circle)
			)
			(primitives
				(gr_poly
					(pts
						(xy 0.1397 0.4064)
						(arc
							(start 0.1397 -0.2667)
							(mid 0 -0.4064)
							(end -0.1397 -0.2667)
						)
						(xy -0.1397 0.4064)
					)
					(width 0)
					(fill yes)
				)
			)
		)
		(pad "14" smd custom
			(at -0.750011 -1.1938)
			(size 0.06985 0.06985)
			(layers "F.Cu" "F.Mask" "F.Paste")
			(net "DEBUG_CPLD_PGRM_JTAG_TMS")
			(options
				(clearance outline)
				(anchor circle)
			)
			(primitives
				(gr_poly
					(pts
						(xy 0.1397 0.4064)
						(arc
							(start 0.1397 -0.2667)
							(mid 0 -0.4064)
							(end -0.1397 -0.2667)
						)
						(xy -0.1397 0.4064)
					)
					(width 0)
					(fill yes)
				)
			)
		)
		(pad "15" smd custom
			(at -1.25001 -1.1938)
			(size 0.06985 0.06985)
			(layers "F.Cu" "F.Mask" "F.Paste")
			(net "9N2032")
			(options
				(clearance outline)
				(anchor circle)
			)
			(primitives
				(gr_poly
					(pts
						(xy 0.1397 0.4064)
						(arc
							(start 0.1397 -0.2667)
							(mid 0 -0.4064)
							(end -0.1397 -0.2667)
						)
						(xy -0.1397 0.4064)
					)
					(width 0)
					(fill yes)
				)
			)
		)
		(pad "16" smd custom
			(at -1.7018 -0.250012 90)
			(size 0.06985 0.06985)
			(layers "F.Cu" "F.Mask" "F.Paste")
			(net "EXT_3.3V")
			(options
				(clearance outline)
				(anchor circle)
			)
			(primitives
				(gr_poly
					(pts
						(xy 0.1397 0.4064)
						(arc
							(start 0.1397 -0.2667)
							(mid 0 -0.4064)
							(end -0.1397 -0.2667)
						)
						(xy -0.1397 0.4064)
					)
					(width 0)
					(fill yes)
				)
			)
		)
		(pad "17" smd rect
			(at 0 0 180)
			(size 1.9812 0.9652)
			(layers "F.Cu" "F.Mask" "F.Paste")
			(net "GND")
		)
		(zone
			(layer "F.Cu")
			(hatch none 0.5)
			(connect_pads
				(clearance 0)
			)
			(min_thickness 0.25)
			(keepout
				(tracks allowed)
				(vias not_allowed)
				(pads allowed)
				(copperpour not_allowed)
				(footprints allowed)
			)
			(placement
				(enabled no)
				(sheetname "")
			)
			(fill
				(thermal_gap 0.5)
				(thermal_bridge_width 0.5)
				(island_removal_mode 0)
			)
			(polygon
				(pts
					(arc
						(start 24.8412 30.734)
						(mid 24.1808 30.734)
						(end 24.8412 30.734)
					)
				)
			)
		)
	)
	(footprint ""
		(layer "F.Cu")
		(at -1.016 33.147)
		(property "Reference" "TP64"
			(at -1.37033 1.778 90)
			(unlocked yes)
			(layer "F.SilkS")
			(effects
				(font
					(size 0.7874 0.5842)
					(thickness 0.127)
				)
				(justify left)
			)
		)
		(property "Value" "*"
			(at -0.4826 -0.14732 0)
			(unlocked yes)
			(layer "F.Fab")
			(hide yes)
			(effects
				(font
					(size 1.27 0.9652)
					(thickness 0.000001)
				)
				(justify left)
			)
		)
		(property "Device Type" "TP_SMALL"
			(at -0.4826 -0.14732 0)
			(unlocked yes)
			(layer "F.Fab")
			(hide yes)
			(effects
				(font
					(size 1.27 0.9652)
					(thickness 0.000001)
				)
				(justify left)
			)
		)
		(duplicate_pad_numbers_are_jumpers no)
		(fp_line
			(start -0.8636 -0.8636)
			(end -0.8636 0.8636)
			(stroke
				(width 0.1524)
				(type default)
			)
			(layer "F.SilkS")
		)
		(fp_line
			(start -0.8636 0.8636)
			(end 0.8636 0.8636)
			(stroke
				(width 0.1524)
				(type default)
			)
			(layer "F.SilkS")
		)
		(fp_line
			(start 0.8636 -0.8636)
			(end -0.8636 -0.8636)
			(stroke
				(width 0.1524)
				(type default)
			)
			(layer "F.SilkS")
		)
		(fp_line
			(start 0.8636 0.8636)
			(end 0.8636 -0.8636)
			(stroke
				(width 0.1524)
				(type default)
			)
			(layer "F.SilkS")
		)
		(fp_poly
			(pts
				(xy -0.635 -0.635) (xy -0.635 0.635) (xy 0.635 0.635) (xy 0.635 -0.635)
			)
			(stroke
				(width 0)
				(type default)
			)
			(fill no)
			(layer "F.CrtYd")
		)
		(pad "1" smd rect
			(at 0 0)
			(size 1.27 1.27)
			(layers "F.Cu" "F.Mask" "F.Paste")
			(net "VDD_7401_PGOOD")
		)
	)
	(footprint ""
		(layer "F.Cu")
		(at 11.303 1.397)
		(property "Reference" "R368"
			(at 0.196012 -1.4732 90)
			(unlocked yes)
			(layer "F.SilkS")
			(effects
				(font
					(size 0.7874 0.5842)
					(thickness 0.127)
				)
				(justify left)
			)
		)
		(property "Value" "0"
			(at -0.148158 1.3462 90)
			(unlocked yes)
			(layer "F.Fab")
			(hide yes)
			(effects
				(font
					(size 1.27 0.9652)
					(thickness 0.000001)
				)
				(justify left)
			)
		)
		(property "Device Type" "REST1111"
			(at -0.148158 1.3462 90)
			(unlocked yes)
			(layer "F.Fab")
			(hide yes)
			(effects
				(font
					(size 1.27 0.9652)
					(thickness 0.000001)
				)
				(justify left)
			)
		)
		(duplicate_pad_numbers_are_jumpers no)
		(fp_poly
			(pts
				(xy 0.635 1.0668) (xy 0.635 -1.0668) (xy -0.635 -1.0668) (xy -0.635 1.0668)
			)
			(stroke
				(width 0)
				(type default)
			)
			(fill no)
			(layer "F.CrtYd")
		)
		(fp_line
			(start -0.254 -0.508)
			(end 0.254 -0.508)
			(stroke
				(width 0.0254)
				(type default)
			)
			(layer "F.Fab")
		)
		(fp_line
			(start -0.254 0.508)
			(end -0.254 -0.508)
			(stroke
				(width 0.0254)
				(type default)
			)
			(layer "F.Fab")
		)
		(fp_line
			(start 0.254 -0.508)
			(end 0.254 0.508)
			(stroke
				(width 0.0254)
				(type default)
			)
			(layer "F.Fab")
		)
		(fp_line
			(start 0.254 0.508)
			(end -0.254 0.508)
			(stroke
				(width 0.0254)
				(type default)
			)
			(layer "F.Fab")
		)
		(pad "1" smd rect
			(at 0 -0.4191)
			(size 0.508 0.5334)
			(layers "F.Cu" "F.Mask" "F.Paste")
			(net "NFP_PCIE0_WAKE_L")
		)
		(pad "2" smd rect
			(at 0 0.4191)
			(size 0.508 0.5334)
			(layers "F.Cu" "F.Mask" "F.Paste")
			(net "PCIE0_WAKE_L")
		)
		(zone
			(layer "F.Cu")
			(hatch none 0.5)
			(connect_pads
				(clearance 0)
			)
			(min_thickness 0.25)
			(keepout
				(tracks not_allowed)
				(vias allowed)
				(pads allowed)
				(copperpour not_allowed)
				(footprints allowed)
			)
			(placement
				(enabled no)
				(sheetname "")
			)
			(fill
				(thermal_gap 0.5)
				(thermal_bridge_width 0.5)
				(island_removal_mode 0)
			)
			(polygon
				(pts
					(xy 11.3284 1.3716) (xy 11.3284 1.4224) (xy 11.2776 1.4224) (xy 11.2776 1.3716)
				)
			)
		)
	)
)
